# BARRELEYE_G2-MB-PVT-X04-HW-BOM-X26_20180122_Final.xls.xlsx — TBD AVL Qual (bom)
| NOTES: |  |  |  |  |  |  |
| The following items are alternates to the items listed in the Critical Components Qual tab. |  |  |  |  |  |  |
| These components will be included on near future, non-customer builds for validation and approval by both Customer and the ODM. |  |  |  |  |  |  |
| Item Description | ODM P/N | Customer PN | Vendor | Vendor PN | Build ?? | Estimated Completion Date |
| SATA connectors (black) |  |  |  |  |  |  |
| -  Alternate |  |  |  |  |  |  |
| SATA connectors (blue) |  |  |  |  |  |  |
| -  Alternate |  |  |  |  |  |  |
| PCIe retention |  |  |  |  |  |  |
| -  Alternate |  |  |  |  |  |  |
| RTC XTAL |  |  |  |  |  |  |
| -  Alternate |  |  |  |  |  |  |
| XTAL |  |  |  |  |  |  |
| -  Alternate |  |  |  |  |  |  |
